(kicad_pcb
	(version 20260206)
	(generator "pcbnew")
	(generator_version "10.0")
	(general
		(thickness 1.6)
		(legacy_teardrops no)
	)
	(paper "A4")
	(title_block
		(title "12092022_DA0F0TMDCD0_F0T_Management_Board_D_brd_V3_OCP.brd")
		(comment 1 "Grand Teton / footprints 839-844 of 1440")
	)
	(layers
		(0 "F.Cu" signal "TOP")
		(4 "In1.Cu" signal "GND")
		(6 "In2.Cu" signal "IN1")
		(8 "In3.Cu" signal "GND1")
		(10 "In4.Cu" signal "IN2")
		(12 "In5.Cu" signal "VCC")
		(14 "In6.Cu" signal "VCC1")
		(16 "In7.Cu" signal "IN3")
		(18 "In8.Cu" signal "GND2")
		(20 "In9.Cu" signal "IN4")
		(22 "In10.Cu" signal "GND3")
		(2 "B.Cu" signal "BOTTOM")
		(9 "F.Adhes" user "F.Adhesive")
		(11 "B.Adhes" user "B.Adhesive")
		(13 "F.Paste" user "Package Geometry/Pastemask Top")
		(15 "B.Paste" user "Package Geometry/Pastemask Bottom")
		(5 "F.SilkS" user "Ref Des/Silkscreen Top")
		(7 "B.SilkS" user "Ref Des/Silkscreen Bottom")
		(1 "F.Mask" user "Board Geometry/Soldermask Top")
		(3 "B.Mask" user "Board Geometry/Soldermask Bottom")
		(17 "Dwgs.User" user "User.Drawings")
		(19 "Cmts.User" user "User.Comments")
		(21 "Eco1.User" user "User.Eco1")
		(23 "Eco2.User" user "User.Eco2")
		(25 "Edge.Cuts" user "Board Geometry/Outline")
		(27 "Margin" user)
		(31 "F.CrtYd" user "Package Geometry/Place Bound Top")
		(29 "B.CrtYd" user "Package Geometry/Place Bound Bottom")
		(35 "F.Fab" user "Ref Des/Assembly Top")
		(33 "B.Fab" user "Ref Des/Assembly Bottom")
	)
	(footprint ""
		(layer "B.Cu")
		(at 57.785 -24.13 -90)
		(property "Reference" "R219"
			(at 0 0 90)
			(layer "B.SilkS")
			(hide yes)
			(effects
				(font
					(size 1.27 1.27)
				)
				(justify mirror)
			)
		)
		(property "Value" ""
			(at 0 0 90)
			(layer "B.Fab")
			(effects
				(font
					(size 1.27 1.27)
				)
				(justify mirror)
			)
		)
		(duplicate_pad_numbers_are_jumpers no)
		(fp_line
			(start -0.7874 0.4064)
			(end 0.7874 0.4064)
			(stroke
				(width 0.1524)
				(type default)
			)
			(layer "B.SilkS")
		)
		(fp_line
			(start 0.7874 0.4064)
			(end 0.7874 -0.4064)
			(stroke
				(width 0.1524)
				(type default)
			)
			(layer "B.SilkS")
		)
		(fp_line
			(start -0.7874 -0.4064)
			(end -0.7874 0.4064)
			(stroke
				(width 0.1524)
				(type default)
			)
			(layer "B.SilkS")
		)
		(fp_line
			(start 0.7874 -0.4064)
			(end -0.7874 -0.4064)
			(stroke
				(width 0.1524)
				(type default)
			)
			(layer "B.SilkS")
		)
		(fp_line
			(start -0.67945 0.3048)
			(end -0.120396 0.3048)
			(stroke
				(width 0.1)
				(type default)
			)
			(layer "B.Fab")
		)
		(fp_line
			(start -0.120396 0.3048)
			(end -0.120396 0.2794)
			(stroke
				(width 0.1)
				(type default)
			)
			(layer "B.Fab")
		)
		(fp_line
			(start 0.12065 0.3048)
			(end 0.67945 0.3048)
			(stroke
				(width 0.1)
				(type default)
			)
			(layer "B.Fab")
		)
		(fp_line
			(start 0.67945 0.3048)
			(end 0.67945 -0.305054)
			(stroke
				(width 0.1)
				(type default)
			)
			(layer "B.Fab")
		)
		(fp_line
			(start -0.120396 0.2794)
			(end 0.12065 0.2794)
			(stroke
				(width 0.1)
				(type default)
			)
			(layer "B.Fab")
		)
		(fp_line
			(start 0.12065 0.2794)
			(end 0.12065 0.3048)
			(stroke
				(width 0.1)
				(type default)
			)
			(layer "B.Fab")
		)
		(fp_line
			(start -0.12065 -0.2794)
			(end -0.12065 -0.3048)
			(stroke
				(width 0.1)
				(type default)
			)
			(layer "B.Fab")
		)
		(fp_line
			(start 0.12065 -0.2794)
			(end -0.12065 -0.2794)
			(stroke
				(width 0.1)
				(type default)
			)
			(layer "B.Fab")
		)
		(fp_line
			(start -0.67945 -0.3048)
			(end -0.67945 0.3048)
			(stroke
				(width 0.1)
				(type default)
			)
			(layer "B.Fab")
		)
		(fp_line
			(start -0.12065 -0.3048)
			(end -0.67945 -0.3048)
			(stroke
				(width 0.1)
				(type default)
			)
			(layer "B.Fab")
		)
		(fp_line
			(start 0.12065 -0.305054)
			(end 0.12065 -0.2794)
			(stroke
				(width 0.1)
				(type default)
			)
			(layer "B.Fab")
		)
		(fp_line
			(start 0.67945 -0.305054)
			(end 0.12065 -0.305054)
			(stroke
				(width 0.1)
				(type default)
			)
			(layer "B.Fab")
		)
		(pad "1" smd circle
			(at 0.40005 0 90)
			(size 0 0)
			(layers "B.Cu" "B.Mask" "B.Paste")
			(net "DEBUG_PORT_UART_TX")
		)
		(pad "2" smd circle
			(at -0.40005 0 90)
			(size 0 0)
			(layers "B.Cu" "B.Mask" "B.Paste")
			(net "GND")
		)
	)
	(footprint ""
		(layer "B.Cu")
		(at 55.08117 -47.85741 -90)
		(property "Reference" "C116"
			(at 0 0 90)
			(layer "B.SilkS")
			(hide yes)
			(effects
				(font
					(size 1.27 1.27)
				)
				(justify mirror)
			)
		)
		(property "Value" ""
			(at 0 0 90)
			(layer "B.Fab")
			(effects
				(font
					(size 1.27 1.27)
				)
				(justify mirror)
			)
		)
		(duplicate_pad_numbers_are_jumpers no)
		(fp_line
			(start -0.7874 0.4064)
			(end 0.7874 0.4064)
			(stroke
				(width 0.1524)
				(type default)
			)
			(layer "B.SilkS")
		)
		(fp_line
			(start 0.7874 0.4064)
			(end 0.7874 -0.4064)
			(stroke
				(width 0.1524)
				(type default)
			)
			(layer "B.SilkS")
		)
		(fp_line
			(start -0.7874 -0.4064)
			(end -0.7874 0.4064)
			(stroke
				(width 0.1524)
				(type default)
			)
			(layer "B.SilkS")
		)
		(fp_line
			(start 0.7874 -0.4064)
			(end -0.7874 -0.4064)
			(stroke
				(width 0.1524)
				(type default)
			)
			(layer "B.SilkS")
		)
		(fp_line
			(start -0.67945 0.3048)
			(end -0.120396 0.3048)
			(stroke
				(width 0.1)
				(type default)
			)
			(layer "B.Fab")
		)
		(fp_line
			(start -0.120396 0.3048)
			(end -0.120396 0.2794)
			(stroke
				(width 0.1)
				(type default)
			)
			(layer "B.Fab")
		)
		(fp_line
			(start 0.12065 0.3048)
			(end 0.67945 0.3048)
			(stroke
				(width 0.1)
				(type default)
			)
			(layer "B.Fab")
		)
		(fp_line
			(start 0.67945 0.3048)
			(end 0.67945 -0.305054)
			(stroke
				(width 0.1)
				(type default)
			)
			(layer "B.Fab")
		)
		(fp_line
			(start -0.120396 0.2794)
			(end 0.12065 0.2794)
			(stroke
				(width 0.1)
				(type default)
			)
			(layer "B.Fab")
		)
		(fp_line
			(start 0.12065 0.2794)
			(end 0.12065 0.3048)
			(stroke
				(width 0.1)
				(type default)
			)
			(layer "B.Fab")
		)
		(fp_line
			(start -0.12065 -0.2794)
			(end -0.12065 -0.3048)
			(stroke
				(width 0.1)
				(type default)
			)
			(layer "B.Fab")
		)
		(fp_line
			(start 0.12065 -0.2794)
			(end -0.12065 -0.2794)
			(stroke
				(width 0.1)
				(type default)
			)
			(layer "B.Fab")
		)
		(fp_line
			(start -0.67945 -0.3048)
			(end -0.67945 0.3048)
			(stroke
				(width 0.1)
				(type default)
			)
			(layer "B.Fab")
		)
		(fp_line
			(start -0.12065 -0.3048)
			(end -0.67945 -0.3048)
			(stroke
				(width 0.1)
				(type default)
			)
			(layer "B.Fab")
		)
		(fp_line
			(start 0.12065 -0.305054)
			(end 0.12065 -0.2794)
			(stroke
				(width 0.1)
				(type default)
			)
			(layer "B.Fab")
		)
		(fp_line
			(start 0.67945 -0.305054)
			(end 0.12065 -0.305054)
			(stroke
				(width 0.1)
				(type default)
			)
			(layer "B.Fab")
		)
		(pad "1" smd circle
			(at 0.40005 0 90)
			(size 0 0)
			(layers "B.Cu" "B.Mask" "B.Paste")
			(net "P1V8_AUX")
		)
		(pad "2" smd circle
			(at -0.40005 0 90)
			(size 0 0)
			(layers "B.Cu" "B.Mask" "B.Paste")
			(net "GND")
		)
	)
	(footprint ""
		(layer "B.Cu")
		(at 63.61811 -62.014862 -90)
		(property "Reference" "R131"
			(at 0 0 90)
			(layer "B.SilkS")
			(hide yes)
			(effects
				(font
					(size 1.27 1.27)
				)
				(justify mirror)
			)
		)
		(property "Value" ""
			(at 0 0 90)
			(layer "B.Fab")
			(effects
				(font
					(size 1.27 1.27)
				)
				(justify mirror)
			)
		)
		(duplicate_pad_numbers_are_jumpers no)
		(fp_line
			(start -0.7874 0.4064)
			(end 0.7874 0.4064)
			(stroke
				(width 0.1524)
				(type default)
			)
			(layer "B.SilkS")
		)
		(fp_line
			(start 0.7874 0.4064)
			(end 0.7874 -0.4064)
			(stroke
				(width 0.1524)
				(type default)
			)
			(layer "B.SilkS")
		)
		(fp_line
			(start -0.7874 -0.4064)
			(end -0.7874 0.4064)
			(stroke
				(width 0.1524)
				(type default)
			)
			(layer "B.SilkS")
		)
		(fp_line
			(start 0.7874 -0.4064)
			(end -0.7874 -0.4064)
			(stroke
				(width 0.1524)
				(type default)
			)
			(layer "B.SilkS")
		)
		(fp_line
			(start -0.67945 0.3048)
			(end -0.120396 0.3048)
			(stroke
				(width 0.1)
				(type default)
			)
			(layer "B.Fab")
		)
		(fp_line
			(start -0.120396 0.3048)
			(end -0.120396 0.2794)
			(stroke
				(width 0.1)
				(type default)
			)
			(layer "B.Fab")
		)
		(fp_line
			(start 0.12065 0.3048)
			(end 0.67945 0.3048)
			(stroke
				(width 0.1)
				(type default)
			)
			(layer "B.Fab")
		)
		(fp_line
			(start 0.67945 0.3048)
			(end 0.67945 -0.305054)
			(stroke
				(width 0.1)
				(type default)
			)
			(layer "B.Fab")
		)
		(fp_line
			(start -0.120396 0.2794)
			(end 0.12065 0.2794)
			(stroke
				(width 0.1)
				(type default)
			)
			(layer "B.Fab")
		)
		(fp_line
			(start 0.12065 0.2794)
			(end 0.12065 0.3048)
			(stroke
				(width 0.1)
				(type default)
			)
			(layer "B.Fab")
		)
		(fp_line
			(start -0.12065 -0.2794)
			(end -0.12065 -0.3048)
			(stroke
				(width 0.1)
				(type default)
			)
			(layer "B.Fab")
		)
		(fp_line
			(start 0.12065 -0.2794)
			(end -0.12065 -0.2794)
			(stroke
				(width 0.1)
				(type default)
			)
			(layer "B.Fab")
		)
		(fp_line
			(start -0.67945 -0.3048)
			(end -0.67945 0.3048)
			(stroke
				(width 0.1)
				(type default)
			)
			(layer "B.Fab")
		)
		(fp_line
			(start -0.12065 -0.3048)
			(end -0.67945 -0.3048)
			(stroke
				(width 0.1)
				(type default)
			)
			(layer "B.Fab")
		)
		(fp_line
			(start 0.12065 -0.305054)
			(end 0.12065 -0.2794)
			(stroke
				(width 0.1)
				(type default)
			)
			(layer "B.Fab")
		)
		(fp_line
			(start 0.67945 -0.305054)
			(end 0.12065 -0.305054)
			(stroke
				(width 0.1)
				(type default)
			)
			(layer "B.Fab")
		)
		(pad "1" smd circle
			(at 0.40005 0 90)
			(size 0 0)
			(layers "B.Cu" "B.Mask" "B.Paste")
			(net "ESPI_LPC_D3_IO3")
		)
		(pad "2" smd circle
			(at -0.40005 0 90)
			(size 0 0)
			(layers "B.Cu" "B.Mask" "B.Paste")
			(net "ESPI_LPC_LAD3_IO3")
		)
	)
	(footprint ""
		(layer "B.Cu")
		(at 85.32241 -27.607768)
		(property "Reference" "R13"
			(at 0 0 0)
			(layer "B.SilkS")
			(hide yes)
			(effects
				(font
					(size 1.27 1.27)
				)
				(justify mirror)
			)
		)
		(property "Value" ""
			(at 0 0 0)
			(layer "B.Fab")
			(effects
				(font
					(size 1.27 1.27)
				)
				(justify mirror)
			)
		)
		(duplicate_pad_numbers_are_jumpers no)
		(fp_line
			(start -0.7874 -0.4064)
			(end -0.7874 0.4064)
			(stroke
				(width 0.1524)
				(type default)
			)
			(layer "B.SilkS")
		)
		(fp_line
			(start -0.7874 0.4064)
			(end 0.7874 0.4064)
			(stroke
				(width 0.1524)
				(type default)
			)
			(layer "B.SilkS")
		)
		(fp_line
			(start 0.7874 -0.4064)
			(end -0.7874 -0.4064)
			(stroke
				(width 0.1524)
				(type default)
			)
			(layer "B.SilkS")
		)
		(fp_line
			(start 0.7874 0.4064)
			(end 0.7874 -0.4064)
			(stroke
				(width 0.1524)
				(type default)
			)
			(layer "B.SilkS")
		)
		(fp_line
			(start -0.67945 -0.3048)
			(end -0.67945 0.3048)
			(stroke
				(width 0.1)
				(type default)
			)
			(layer "B.Fab")
		)
		(fp_line
			(start -0.67945 0.3048)
			(end -0.120396 0.3048)
			(stroke
				(width 0.1)
				(type default)
			)
			(layer "B.Fab")
		)
		(fp_line
			(start -0.12065 -0.3048)
			(end -0.67945 -0.3048)
			(stroke
				(width 0.1)
				(type default)
			)
			(layer "B.Fab")
		)
		(fp_line
			(start -0.12065 -0.2794)
			(end -0.12065 -0.3048)
			(stroke
				(width 0.1)
				(type default)
			)
			(layer "B.Fab")
		)
		(fp_line
			(start -0.120396 0.2794)
			(end 0.12065 0.2794)
			(stroke
				(width 0.1)
				(type default)
			)
			(layer "B.Fab")
		)
		(fp_line
			(start -0.120396 0.3048)
			(end -0.120396 0.2794)
			(stroke
				(width 0.1)
				(type default)
			)
			(layer "B.Fab")
		)
		(fp_line
			(start 0.12065 -0.305054)
			(end 0.12065 -0.2794)
			(stroke
				(width 0.1)
				(type default)
			)
			(layer "B.Fab")
		)
		(fp_line
			(start 0.12065 -0.2794)
			(end -0.12065 -0.2794)
			(stroke
				(width 0.1)
				(type default)
			)
			(layer "B.Fab")
		)
		(fp_line
			(start 0.12065 0.2794)
			(end 0.12065 0.3048)
			(stroke
				(width 0.1)
				(type default)
			)
			(layer "B.Fab")
		)
		(fp_line
			(start 0.12065 0.3048)
			(end 0.67945 0.3048)
			(stroke
				(width 0.1)
				(type default)
			)
			(layer "B.Fab")
		)
		(fp_line
			(start 0.67945 -0.305054)
			(end 0.12065 -0.305054)
			(stroke
				(width 0.1)
				(type default)
			)
			(layer "B.Fab")
		)
		(fp_line
			(start 0.67945 0.3048)
			(end 0.67945 -0.305054)
			(stroke
				(width 0.1)
				(type default)
			)
			(layer "B.Fab")
		)
		(pad "1" smd circle
			(at 0.40005 0 180)
			(size 0 0)
			(layers "B.Cu" "B.Mask" "B.Paste")
			(net "P3V3_AUX")
		)
		(pad "2" smd circle
			(at -0.40005 0 180)
			(size 0 0)
			(layers "B.Cu" "B.Mask" "B.Paste")
			(net "FRU_E1")
		)
	)
	(footprint ""
		(layer "B.Cu")
		(at 38.608 -64.5922 90)
		(property "Reference" "R644"
			(at 0 0 90)
			(layer "B.SilkS")
			(hide yes)
			(effects
				(font
					(size 1.27 1.27)
				)
				(justify mirror)
			)
		)
		(property "Value" ""
			(at 0 0 90)
			(layer "B.Fab")
			(effects
				(font
					(size 1.27 1.27)
				)
				(justify mirror)
			)
		)
		(duplicate_pad_numbers_are_jumpers no)
		(fp_line
			(start 0.7874 -0.4064)
			(end -0.7874 -0.4064)
			(stroke
				(width 0.1524)
				(type default)
			)
			(layer "B.SilkS")
		)
		(fp_line
			(start -0.7874 -0.4064)
			(end -0.7874 0.4064)
			(stroke
				(width 0.1524)
				(type default)
			)
			(layer "B.SilkS")
		)
		(fp_line
			(start 0.7874 0.4064)
			(end 0.7874 -0.4064)
			(stroke
				(width 0.1524)
				(type default)
			)
			(layer "B.SilkS")
		)
		(fp_line
			(start -0.7874 0.4064)
			(end 0.7874 0.4064)
			(stroke
				(width 0.1524)
				(type default)
			)
			(layer "B.SilkS")
		)
		(fp_line
			(start 0.67945 -0.305054)
			(end 0.12065 -0.305054)
			(stroke
				(width 0.1)
				(type default)
			)
			(layer "B.Fab")
		)
		(fp_line
			(start 0.12065 -0.305054)
			(end 0.12065 -0.2794)
			(stroke
				(width 0.1)
				(type default)
			)
			(layer "B.Fab")
		)
		(fp_line
			(start -0.12065 -0.3048)
			(end -0.67945 -0.3048)
			(stroke
				(width 0.1)
				(type default)
			)
			(layer "B.Fab")
		)
		(fp_line
			(start -0.67945 -0.3048)
			(end -0.67945 0.3048)
			(stroke
				(width 0.1)
				(type default)
			)
			(layer "B.Fab")
		)
		(fp_line
			(start 0.12065 -0.2794)
			(end -0.12065 -0.2794)
			(stroke
				(width 0.1)
				(type default)
			)
			(layer "B.Fab")
		)
		(fp_line
			(start -0.12065 -0.2794)
			(end -0.12065 -0.3048)
			(stroke
				(width 0.1)
				(type default)
			)
			(layer "B.Fab")
		)
		(fp_line
			(start 0.12065 0.2794)
			(end 0.12065 0.3048)
			(stroke
				(width 0.1)
				(type default)
			)
			(layer "B.Fab")
		)
		(fp_line
			(start -0.120396 0.2794)
			(end 0.12065 0.2794)
			(stroke
				(width 0.1)
				(type default)
			)
			(layer "B.Fab")
		)
		(fp_line
			(start 0.67945 0.3048)
			(end 0.67945 -0.305054)
			(stroke
				(width 0.1)
				(type default)
			)
			(layer "B.Fab")
		)
		(fp_line
			(start 0.12065 0.3048)
			(end 0.67945 0.3048)
			(stroke
				(width 0.1)
				(type default)
			)
			(layer "B.Fab")
		)
		(fp_line
			(start -0.120396 0.3048)
			(end -0.120396 0.2794)
			(stroke
				(width 0.1)
				(type default)
			)
			(layer "B.Fab")
		)
		(fp_line
			(start -0.67945 0.3048)
			(end -0.120396 0.3048)
			(stroke
				(width 0.1)
				(type default)
			)
			(layer "B.Fab")
		)
		(pad "1" smd circle
			(at 0.40005 0 270)
			(size 0 0)
			(layers "B.Cu" "B.Mask" "B.Paste")
			(net "FM_JTAG_BMC_MUX_SEL")
		)
		(pad "2" smd circle
			(at -0.40005 0 270)
			(size 0 0)
			(layers "B.Cu" "B.Mask" "B.Paste")
			(net "FM_JTAG_BMC_MUX_SEL_R1")
		)
	)
	(footprint ""
		(layer "B.Cu")
		(at 21.059394 -95.187008 90)
		(property "Reference" "C245"
			(at 0 0 90)
			(layer "B.SilkS")
			(hide yes)
			(effects
				(font
					(size 1.27 1.27)
				)
				(justify mirror)
			)
		)
		(property "Value" ""
			(at 0 0 90)
			(layer "B.Fab")
			(effects
				(font
					(size 1.27 1.27)
				)
				(justify mirror)
			)
		)
		(duplicate_pad_numbers_are_jumpers no)
		(fp_line
			(start 0.69215 -0.2921)
			(end -0.69215 -0.2921)
			(stroke
				(width 0.1524)
				(type default)
			)
			(layer "B.SilkS")
		)
		(fp_line
			(start -0.69215 -0.2921)
			(end -0.69215 0.2921)
			(stroke
				(width 0.1524)
				(type default)
			)
			(layer "B.SilkS")
		)
		(fp_line
			(start 0.69215 0.2921)
			(end 0.69215 -0.2921)
			(stroke
				(width 0.1524)
				(type default)
			)
			(layer "B.SilkS")
		)
		(fp_line
			(start -0.69215 0.2921)
			(end 0.69215 0.2921)
			(stroke
				(width 0.1524)
				(type default)
			)
			(layer "B.SilkS")
		)
		(fp_line
			(start 0.51435 -0.2794)
			(end -0.51435 -0.2794)
			(stroke
				(width 0.1)
				(type default)
			)
			(layer "B.Fab")
		)
		(fp_line
			(start -0.51435 -0.2794)
			(end -0.51435 0.2794)
			(stroke
				(width 0.1)
				(type default)
			)
			(layer "B.Fab")
		)
		(fp_line
			(start 0.51435 0.2794)
			(end 0.51435 -0.2794)
			(stroke
				(width 0.1)
				(type default)
			)
			(layer "B.Fab")
		)
		(fp_line
			(start -0.51435 0.2794)
			(end 0.51435 0.2794)
			(stroke
				(width 0.1)
				(type default)
			)
			(layer "B.Fab")
		)
		(pad "1" smd circle
			(at 0.40005 0 270)
			(size 0 0)
			(layers "B.Cu" "B.Mask" "B.Paste")
			(net "VCCIO2")
		)
		(pad "2" smd circle
			(at -0.40005 0 270)
			(size 0 0)
			(layers "B.Cu" "B.Mask" "B.Paste")
			(net "GND")
		)
		(zone
			(layer "B.Cu")
			(hatch none 0.5)
			(connect_pads
				(clearance 0)
			)
			(min_thickness 0.25)
			(keepout
				(tracks not_allowed)
				(vias allowed)
				(pads allowed)
				(copperpour not_allowed)
				(footprints allowed)
			)
			(placement
				(enabled no)
				(sheetname "")
			)
			(fill
				(thermal_gap 0.5)
				(thermal_bridge_width 0.5)
				(island_removal_mode 0)
			)
			(polygon
				(pts
					(xy 21.147024 -95.377508) (xy 21.20519 -95.286068) (xy 21.20519 -95.086678) (xy 21.147024 -94.996508)
					(xy 20.971764 -94.996508) (xy 20.913344 -95.086678) (xy 20.913344 -95.286068) (xy 20.97151 -95.377508)
				)
			)
		)
	)
)
